(kicad_pcb
	(version 20260206)
	(generator "pcbnew")
	(generator_version "10.0")
	(general
		(thickness 1.6)
		(legacy_teardrops no)
	)
	(paper "A4")
	(title_block
		(title "v2-tray-backplane — ms_tbp_v2.brd")
		(comment 1 "Open CloudServer (Microsoft) / footprints 123-131 of 164")
	)
	(layers
		(0 "F.Cu" signal "TOP")
		(4 "In1.Cu" signal "LYR2")
		(6 "In2.Cu" signal "LYR3")
		(8 "In3.Cu" signal "LYR4")
		(10 "In4.Cu" signal "LYR5")
		(12 "In5.Cu" signal "LYR6")
		(14 "In6.Cu" signal "LYR7")
		(2 "B.Cu" signal "BOTTOM")
		(9 "F.Adhes" user "F.Adhesive")
		(11 "B.Adhes" user "B.Adhesive")
		(13 "F.Paste" user "Package Geometry/Pastemask Top")
		(15 "B.Paste" user "Package Geometry/Pastemask Bottom")
		(5 "F.SilkS" user "Ref Des/Silkscreen Top")
		(7 "B.SilkS" user "Ref Des/Silkscreen Bottom")
		(1 "F.Mask" user "Board Geometry/Soldermask Top")
		(3 "B.Mask" user "Board Geometry/Soldermask Bottom")
		(17 "Dwgs.User" user "User.Drawings")
		(19 "Cmts.User" user "User.Comments")
		(21 "Eco1.User" user "User.Eco1")
		(23 "Eco2.User" user "User.Eco2")
		(25 "Edge.Cuts" user "Board Geometry/Outline")
		(27 "Margin" user)
		(31 "F.CrtYd" user "Package Geometry/Place Bound Top")
		(29 "B.CrtYd" user "Package Geometry/Place Bound Bottom")
		(35 "F.Fab" user "Ref Des/Assembly Top")
		(33 "B.Fab" user "Ref Des/Assembly Bottom")
	)
	(footprint ""
		(layer "F.Cu")
		(at -19.9136 44.196 -90)
		(property "Reference" "R71"
			(at 0.254 -2.0447 90)
			(unlocked yes)
			(layer "F.SilkS")
			(effects
				(font
					(size 0.762 0.5334)
					(thickness 0.1016)
				)
			)
		)
		(property "Value" ""
			(at 0 0 270)
			(layer "F.Fab")
			(effects
				(font
					(size 1.27 1.27)
				)
			)
		)
		(duplicate_pad_numbers_are_jumpers no)
		(fp_line
			(start 0 -0.381)
			(end 0 0.381)
			(stroke
				(width 0.127)
				(type default)
			)
			(layer "F.SilkS")
		)
		(fp_poly
			(pts
				(xy 1.255601 0.6564) (xy -1.255601 0.6564) (xy -1.255601 -0.656399) (xy 1.255601 -0.656399)
			)
			(stroke
				(width 0)
				(type default)
			)
			(fill no)
			(layer "F.CrtYd")
		)
		(fp_line
			(start -0.800001 0.399999)
			(end 0.800001 0.399999)
			(stroke
				(width 0.1)
				(type default)
			)
			(layer "F.Fab")
		)
		(fp_line
			(start 0.800001 0.399999)
			(end 0.800001 -0.399999)
			(stroke
				(width 0.1)
				(type default)
			)
			(layer "F.Fab")
		)
		(fp_line
			(start -0.800001 -0.399999)
			(end -0.800001 0.399999)
			(stroke
				(width 0.1)
				(type default)
			)
			(layer "F.Fab")
		)
		(fp_line
			(start 0.800001 -0.399999)
			(end -0.800001 -0.399999)
			(stroke
				(width 0.1)
				(type default)
			)
			(layer "F.Fab")
		)
		(pad "1" smd rect
			(at -0.650001 0 270)
			(size 0.7112 0.8128)
			(layers "F.Cu" "F.Mask" "F.Paste")
			(net "GND")
		)
		(pad "2" smd rect
			(at 0.650001 0 90)
			(size 0.7112 0.8128)
			(layers "F.Cu" "F.Mask" "F.Paste")
			(net "JBOD_B2_MATED_N")
		)
	)
	(footprint ""
		(layer "F.Cu")
		(at -331.47 14.6558)
		(property "Reference" "R82"
			(at 3.175 0.1143 0)
			(unlocked yes)
			(layer "F.SilkS")
			(effects
				(font
					(size 0.762 0.5334)
					(thickness 0.1016)
				)
			)
		)
		(property "Value" ""
			(at 0 0 0)
			(layer "F.Fab")
			(effects
				(font
					(size 1.27 1.27)
				)
			)
		)
		(duplicate_pad_numbers_are_jumpers no)
		(fp_line
			(start 0 -0.381)
			(end 0 0.381)
			(stroke
				(width 0.127)
				(type default)
			)
			(layer "F.SilkS")
		)
		(fp_poly
			(pts
				(xy 1.255601 0.6564) (xy -1.255601 0.6564) (xy -1.255601 -0.656399) (xy 1.255601 -0.656399)
			)
			(stroke
				(width 0)
				(type default)
			)
			(fill no)
			(layer "F.CrtYd")
		)
		(fp_line
			(start -0.800001 -0.399999)
			(end -0.800001 0.399999)
			(stroke
				(width 0.1)
				(type default)
			)
			(layer "F.Fab")
		)
		(fp_line
			(start -0.800001 0.399999)
			(end 0.800001 0.399999)
			(stroke
				(width 0.1)
				(type default)
			)
			(layer "F.Fab")
		)
		(fp_line
			(start 0.800001 -0.399999)
			(end -0.800001 -0.399999)
			(stroke
				(width 0.1)
				(type default)
			)
			(layer "F.Fab")
		)
		(fp_line
			(start 0.800001 0.399999)
			(end 0.800001 -0.399999)
			(stroke
				(width 0.1)
				(type default)
			)
			(layer "F.Fab")
		)
		(pad "1" smd rect
			(at -0.650001 0)
			(size 0.7112 0.8128)
			(layers "F.Cu" "F.Mask" "F.Paste")
			(net "P3V3_B1_QSFP")
		)
		(pad "2" smd rect
			(at 0.650001 0 180)
			(size 0.7112 0.8128)
			(layers "F.Cu" "F.Mask" "F.Paste")
			(net "ETH40G_B1_SCL")
		)
	)
	(footprint ""
		(layer "F.Cu")
		(at -201.607001 41.110002 90)
		(property "Reference" "U3"
			(at 9.194902 0.439001 0)
			(unlocked yes)
			(layer "F.SilkS")
			(effects
				(font
					(size 0.762 0.5334)
					(thickness 0.1016)
				)
			)
		)
		(property "Value" ""
			(at 0 0 90)
			(layer "F.Fab")
			(effects
				(font
					(size 1.27 1.27)
				)
			)
		)
		(duplicate_pad_numbers_are_jumpers no)
		(fp_line
			(start 8 -1.749999)
			(end 6.5 -1.749999)
			(stroke
				(width 0.127)
				(type default)
			)
			(layer "F.SilkS")
		)
		(fp_line
			(start -0.499999 -1.749999)
			(end -2.000001 -1.749999)
			(stroke
				(width 0.127)
				(type default)
			)
			(layer "F.SilkS")
		)
		(fp_line
			(start -2.000001 -1.749999)
			(end -2.000001 -0.249999)
			(stroke
				(width 0.127)
				(type default)
			)
			(layer "F.SilkS")
		)
		(fp_line
			(start 8 -0.249999)
			(end 8 -1.749999)
			(stroke
				(width 0.127)
				(type default)
			)
			(layer "F.SilkS")
		)
		(fp_line
			(start -2.000001 1.45)
			(end -2.000001 2.949999)
			(stroke
				(width 0.127)
				(type default)
			)
			(layer "F.SilkS")
		)
		(fp_line
			(start 8 2.949999)
			(end 8 1.45)
			(stroke
				(width 0.127)
				(type default)
			)
			(layer "F.SilkS")
		)
		(fp_line
			(start 6.5 2.949999)
			(end 8 2.949999)
			(stroke
				(width 0.127)
				(type default)
			)
			(layer "F.SilkS")
		)
		(fp_line
			(start -2.000001 2.949999)
			(end -0.499999 2.949999)
			(stroke
				(width 0.127)
				(type default)
			)
			(layer "F.SilkS")
		)
		(fp_poly
			(pts
				(arc
					(start 6.000001 -5.21)
					(mid 11.210001 0)
					(end 6.000001 5.21)
				)
				(arc
					(start 0 5.21)
					(mid -5.21 0)
					(end 0 -5.21)
				)
			)
			(stroke
				(width 0)
				(type default)
			)
			(fill no)
			(layer "B.CrtYd")
		)
		(fp_poly
			(pts
				(xy -2.5 -2.25) (xy 8.500001 -2.25) (xy 8.500001 3.450001) (xy -2.5 3.450001)
			)
			(stroke
				(width 0)
				(type default)
			)
			(fill no)
			(layer "F.CrtYd")
		)
		(fp_line
			(start 8 -1.749999)
			(end -2.000001 -1.749999)
			(stroke
				(width 0.1)
				(type default)
			)
			(layer "F.Fab")
		)
		(fp_line
			(start -2.000001 -1.749999)
			(end -2.000001 2.949999)
			(stroke
				(width 0.1)
				(type default)
			)
			(layer "F.Fab")
		)
		(fp_line
			(start 8 2.949999)
			(end 8 -1.749999)
			(stroke
				(width 0.1)
				(type default)
			)
			(layer "F.Fab")
		)
		(fp_line
			(start -2.000001 2.949999)
			(end 8 2.949999)
			(stroke
				(width 0.1)
				(type default)
			)
			(layer "F.Fab")
		)
		(fp_text user "4"
			(at 6.019902 -2.735999 0)
			(unlocked yes)
			(layer "F.SilkS")
			(effects
				(font
					(size 0.762 0.5334)
					(thickness 0.1016)
				)
			)
		)
		(fp_text user "*"
			(at 0 -2.371451 90)
			(unlocked yes)
			(layer "F.SilkS")
			(effects
				(font
					(size 0.381 0.381)
					(thickness 0.381)
				)
			)
		)
		(fp_text user "*"
			(at 0 -1.47145 90)
			(unlocked yes)
			(layer "B.SilkS")
			(effects
				(font
					(size 0.381 0.381)
					(thickness 0.381)
				)
				(justify mirror)
			)
		)
		(fp_text user "4"
			(at 5.892902 -1.465999 0)
			(unlocked yes)
			(layer "B.SilkS")
			(effects
				(font
					(size 0.762 0.5334)
					(thickness 0.1016)
				)
				(justify mirror)
			)
		)
		(pad "1" thru_hole circle
			(at 0 0 90)
			(size 1.3716 1.3716)
			(drill 1.016)
			(layers "*.Cu" "*.Mask")
			(remove_unused_layers no)
			(net "P5V_USB_B2")
		)
		(pad "2" thru_hole circle
			(at 2.000001 0 90)
			(size 1.3716 1.3716)
			(drill 1.016)
			(layers "*.Cu" "*.Mask")
			(remove_unused_layers no)
			(net "USB_B2_N")
		)
		(pad "3" thru_hole circle
			(at 4 0 90)
			(size 1.3716 1.3716)
			(drill 1.016)
			(layers "*.Cu" "*.Mask")
			(remove_unused_layers no)
			(net "USB_B2_P")
		)
		(pad "4" thru_hole circle
			(at 6.000001 0 90)
			(size 1.3716 1.3716)
			(drill 1.016)
			(layers "*.Cu" "*.Mask")
			(remove_unused_layers no)
			(net "GND")
		)
	)
	(footprint ""
		(layer "F.Cu")
		(at -353.3902 34.29 90)
		(property "Reference" "C3"
			(at -2.032 -0.0889 90)
			(unlocked yes)
			(layer "F.SilkS")
			(effects
				(font
					(size 0.762 0.5334)
					(thickness 0.1016)
				)
			)
		)
		(property "Value" ""
			(at 0 0 90)
			(layer "F.Fab")
			(effects
				(font
					(size 1.27 1.27)
				)
			)
		)
		(duplicate_pad_numbers_are_jumpers no)
		(fp_poly
			(pts
				(xy -0.9993 0.503999) (xy -0.9993 -0.504) (xy 0.999299 -0.504) (xy 0.999299 0.503999)
			)
			(stroke
				(width 0)
				(type default)
			)
			(fill no)
			(layer "F.CrtYd")
		)
		(fp_line
			(start 0.499999 -0.25)
			(end 0.499999 0.249999)
			(stroke
				(width 0.1)
				(type default)
			)
			(layer "F.Fab")
		)
		(fp_line
			(start -0.499999 -0.25)
			(end 0.499999 -0.25)
			(stroke
				(width 0.1)
				(type default)
			)
			(layer "F.Fab")
		)
		(fp_line
			(start 0.499999 0.249999)
			(end -0.499999 0.249999)
			(stroke
				(width 0.1)
				(type default)
			)
			(layer "F.Fab")
		)
		(fp_line
			(start -0.499999 0.249999)
			(end -0.499999 -0.25)
			(stroke
				(width 0.1)
				(type default)
			)
			(layer "F.Fab")
		)
		(pad "1" smd rect
			(at -0.4572 0 180)
			(size 0.508 0.5842)
			(layers "F.Cu" "F.Mask" "F.Paste")
			(net "P12V")
		)
		(pad "2" smd rect
			(at 0.4572 0 180)
			(size 0.508 0.5842)
			(layers "F.Cu" "F.Mask" "F.Paste")
			(net "GND")
		)
	)
	(footprint ""
		(layer "F.Cu")
		(at -80.098798 3.461601)
		(property "Reference" "R55"
			(at -3.213202 -0.121501 0)
			(unlocked yes)
			(layer "F.SilkS")
			(effects
				(font
					(size 0.762 0.5334)
					(thickness 0.1016)
				)
			)
		)
		(property "Value" ""
			(at 0 0 0)
			(layer "F.Fab")
			(effects
				(font
					(size 1.27 1.27)
				)
			)
		)
		(duplicate_pad_numbers_are_jumpers no)
		(fp_line
			(start 0 -0.381)
			(end 0 0.381)
			(stroke
				(width 0.127)
				(type default)
			)
			(layer "F.SilkS")
		)
		(fp_poly
			(pts
				(xy 1.2556 0.656399) (xy -1.255601 0.656399) (xy -1.255601 -0.6564) (xy 1.2556 -0.6564)
			)
			(stroke
				(width 0)
				(type default)
			)
			(fill no)
			(layer "F.CrtYd")
		)
		(fp_line
			(start -0.800001 -0.399999)
			(end -0.800001 0.399999)
			(stroke
				(width 0.1)
				(type default)
			)
			(layer "F.Fab")
		)
		(fp_line
			(start -0.800001 0.399999)
			(end 0.800001 0.399999)
			(stroke
				(width 0.1)
				(type default)
			)
			(layer "F.Fab")
		)
		(fp_line
			(start 0.800001 -0.399999)
			(end -0.800001 -0.399999)
			(stroke
				(width 0.1)
				(type default)
			)
			(layer "F.Fab")
		)
		(fp_line
			(start 0.800001 0.399999)
			(end 0.800001 -0.399999)
			(stroke
				(width 0.1)
				(type default)
			)
			(layer "F.Fab")
		)
		(pad "1" smd rect
			(at -0.650001 0)
			(size 0.7112 0.8128)
			(layers "F.Cu" "F.Mask" "F.Paste")
			(net "P3V3_B2_QSFP")
		)
		(pad "2" smd rect
			(at 0.650001 0 180)
			(size 0.7112 0.8128)
			(layers "F.Cu" "F.Mask" "F.Paste")
			(net "ETH10G_B2_RX_LOS")
		)
	)
	(footprint ""
		(layer "F.Cu")
		(at -331.47 9.0678)
		(property "Reference" "R78"
			(at 3.175 0.1143 0)
			(unlocked yes)
			(layer "F.SilkS")
			(effects
				(font
					(size 0.762 0.5334)
					(thickness 0.1016)
				)
			)
		)
		(property "Value" ""
			(at 0 0 0)
			(layer "F.Fab")
			(effects
				(font
					(size 1.27 1.27)
				)
			)
		)
		(duplicate_pad_numbers_are_jumpers no)
		(fp_line
			(start 0 -0.381)
			(end 0 0.381)
			(stroke
				(width 0.127)
				(type default)
			)
			(layer "F.SilkS")
		)
		(fp_poly
			(pts
				(xy 1.255601 0.6564) (xy -1.255601 0.6564) (xy -1.255601 -0.656399) (xy 1.255601 -0.656399)
			)
			(stroke
				(width 0)
				(type default)
			)
			(fill no)
			(layer "F.CrtYd")
		)
		(fp_line
			(start -0.800001 -0.399999)
			(end -0.800001 0.399999)
			(stroke
				(width 0.1)
				(type default)
			)
			(layer "F.Fab")
		)
		(fp_line
			(start -0.800001 0.399999)
			(end 0.800001 0.399999)
			(stroke
				(width 0.1)
				(type default)
			)
			(layer "F.Fab")
		)
		(fp_line
			(start 0.800001 -0.399999)
			(end -0.800001 -0.399999)
			(stroke
				(width 0.1)
				(type default)
			)
			(layer "F.Fab")
		)
		(fp_line
			(start 0.800001 0.399999)
			(end 0.800001 -0.399999)
			(stroke
				(width 0.1)
				(type default)
			)
			(layer "F.Fab")
		)
		(pad "1" smd rect
			(at -0.650001 0)
			(size 0.7112 0.8128)
			(layers "F.Cu" "F.Mask" "F.Paste")
			(net "P3V3_B1_QSFP")
		)
		(pad "2" smd rect
			(at 0.650001 0 180)
			(size 0.7112 0.8128)
			(layers "F.Cu" "F.Mask" "F.Paste")
			(net "ETH40G_B1_INT_N")
		)
	)
	(footprint ""
		(layer "F.Cu")
		(at -418.846 30.861 90)
		(property "Reference" "U2"
			(at 3.1369 4.318 0)
			(unlocked yes)
			(layer "F.SilkS")
			(effects
				(font
					(size 0.762 0.5334)
					(thickness 0.1016)
				)
			)
		)
		(property "Value" ""
			(at 0 0 90)
			(layer "F.Fab")
			(effects
				(font
					(size 1.27 1.27)
				)
			)
		)
		(duplicate_pad_numbers_are_jumpers no)
		(fp_line
			(start 7.999999 -1.749999)
			(end 6.5 -1.749999)
			(stroke
				(width 0.127)
				(type default)
			)
			(layer "F.SilkS")
		)
		(fp_line
			(start -0.499999 -1.749999)
			(end -2.000001 -1.749999)
			(stroke
				(width 0.127)
				(type default)
			)
			(layer "F.SilkS")
		)
		(fp_line
			(start -2.000001 -1.749999)
			(end -2.000001 -0.25)
			(stroke
				(width 0.127)
				(type default)
			)
			(layer "F.SilkS")
		)
		(fp_line
			(start 7.999999 -0.25)
			(end 7.999999 -1.749999)
			(stroke
				(width 0.127)
				(type default)
			)
			(layer "F.SilkS")
		)
		(fp_line
			(start -2.000001 1.45)
			(end -2.000001 2.949999)
			(stroke
				(width 0.127)
				(type default)
			)
			(layer "F.SilkS")
		)
		(fp_line
			(start 7.999999 2.949999)
			(end 7.999999 1.45)
			(stroke
				(width 0.127)
				(type default)
			)
			(layer "F.SilkS")
		)
		(fp_line
			(start 6.5 2.949999)
			(end 7.999999 2.949999)
			(stroke
				(width 0.127)
				(type default)
			)
			(layer "F.SilkS")
		)
		(fp_line
			(start -2.000001 2.949999)
			(end -0.499999 2.949999)
			(stroke
				(width 0.127)
				(type default)
			)
			(layer "F.SilkS")
		)
		(fp_poly
			(pts
				(arc
					(start 6.000001 -5.21)
					(mid 11.210001 0)
					(end 6.000001 5.21)
				)
				(arc
					(start 0 5.21)
					(mid -5.21 0)
					(end 0 -5.21)
				)
			)
			(stroke
				(width 0)
				(type default)
			)
			(fill no)
			(layer "B.CrtYd")
		)
		(fp_poly
			(pts
				(xy -2.5 -2.250001) (xy 8.500001 -2.250001) (xy 8.500001 3.450001) (xy -2.5 3.450001)
			)
			(stroke
				(width 0)
				(type default)
			)
			(fill no)
			(layer "F.CrtYd")
		)
		(fp_line
			(start 7.999999 -1.749999)
			(end -2.000001 -1.749999)
			(stroke
				(width 0.1)
				(type default)
			)
			(layer "F.Fab")
		)
		(fp_line
			(start -2.000001 -1.749999)
			(end -2.000001 2.949999)
			(stroke
				(width 0.1)
				(type default)
			)
			(layer "F.Fab")
		)
		(fp_line
			(start 7.999999 2.949999)
			(end 7.999999 -1.749999)
			(stroke
				(width 0.1)
				(type default)
			)
			(layer "F.Fab")
		)
		(fp_line
			(start -2.000001 2.949999)
			(end 7.999999 2.949999)
			(stroke
				(width 0.1)
				(type default)
			)
			(layer "F.Fab")
		)
		(fp_text user "4"
			(at 5.638902 -2.481999 0)
			(unlocked yes)
			(layer "F.SilkS")
			(effects
				(font
					(size 0.762 0.5334)
					(thickness 0.1016)
				)
			)
		)
		(fp_text user "*"
			(at 0 -2.371451 90)
			(unlocked yes)
			(layer "F.SilkS")
			(effects
				(font
					(size 0.381 0.381)
					(thickness 0.381)
				)
			)
		)
		(fp_text user "4"
			(at 6.146902 -1.592999 0)
			(unlocked yes)
			(layer "B.SilkS")
			(effects
				(font
					(size 0.762 0.5334)
					(thickness 0.1016)
				)
				(justify mirror)
			)
		)
		(fp_text user "*"
			(at 0 -1.47145 90)
			(unlocked yes)
			(layer "B.SilkS")
			(effects
				(font
					(size 0.381 0.381)
					(thickness 0.381)
				)
				(justify mirror)
			)
		)
		(pad "1" thru_hole circle
			(at 0 0 90)
			(size 1.3716 1.3716)
			(drill 1.016)
			(layers "*.Cu" "*.Mask")
			(remove_unused_layers no)
			(net "P5V_USB_B1")
		)
		(pad "2" thru_hole circle
			(at 2.000001 0 90)
			(size 1.3716 1.3716)
			(drill 1.016)
			(layers "*.Cu" "*.Mask")
			(remove_unused_layers no)
			(net "USB_B1_N")
		)
		(pad "3" thru_hole circle
			(at 4 0 90)
			(size 1.3716 1.3716)
			(drill 1.016)
			(layers "*.Cu" "*.Mask")
			(remove_unused_layers no)
			(net "USB_B1_P")
		)
		(pad "4" thru_hole circle
			(at 6.000001 0 90)
			(size 1.3716 1.3716)
			(drill 1.016)
			(layers "*.Cu" "*.Mask")
			(remove_unused_layers no)
			(net "GND")
		)
	)
	(footprint ""
		(layer "F.Cu")
		(at -65.9638 45.72)
		(property "Reference" "FS3"
			(at 0.0508 1.0541 0)
			(unlocked yes)
			(layer "F.SilkS")
			(effects
				(font
					(size 0.762 0.5334)
					(thickness 0.1016)
				)
			)
		)
		(property "Value" ""
			(at 0 0 0)
			(layer "F.Fab")
			(effects
				(font
					(size 1.27 1.27)
				)
			)
		)
		(duplicate_pad_numbers_are_jumpers no)
		(fp_poly
			(pts
				(xy -1.002101 0.504) (xy -1.002101 -0.503999) (xy 1.002101 -0.503999) (xy 1.002101 0.504)
			)
			(stroke
				(width 0)
				(type default)
			)
			(fill no)
			(layer "F.CrtYd")
		)
		(fp_line
			(start -0.499999 -0.249999)
			(end -0.499999 0.25)
			(stroke
				(width 0.1)
				(type default)
			)
			(layer "F.Fab")
		)
		(fp_line
			(start -0.499999 0.25)
			(end 0.499999 0.25)
			(stroke
				(width 0.1)
				(type default)
			)
			(layer "F.Fab")
		)
		(fp_line
			(start 0.499999 -0.249999)
			(end -0.499999 -0.249999)
			(stroke
				(width 0.1)
				(type default)
			)
			(layer "F.Fab")
		)
		(fp_line
			(start 0.499999 0.25)
			(end 0.499999 -0.249999)
			(stroke
				(width 0.1)
				(type default)
			)
			(layer "F.Fab")
		)
		(pad "1" smd rect
			(at -0.459999 0 90)
			(size 0.508 0.5842)
			(layers "F.Cu" "F.Mask" "F.Paste")
			(net "P3V3_B2_QSFP")
		)
		(pad "2" smd rect
			(at 0.459999 0 90)
			(size 0.508 0.5842)
			(layers "F.Cu" "F.Mask" "F.Paste")
			(net "UNNAMED_6_FERRITE_I24_A")
		)
	)
	(footprint ""
		(layer "F.Cu")
		(at -75.292801 1.130402)
		(property "Reference" "R46"
			(at 3.029801 0.050698 0)
			(unlocked yes)
			(layer "F.SilkS")
			(effects
				(font
					(size 0.762 0.5334)
					(thickness 0.1016)
				)
			)
		)
		(property "Value" ""
			(at 0 0 0)
			(layer "F.Fab")
			(effects
				(font
					(size 1.27 1.27)
				)
			)
		)
		(duplicate_pad_numbers_are_jumpers no)
		(fp_line
			(start 0 -0.381)
			(end 0 0.381)
			(stroke
				(width 0.127)
				(type default)
			)
			(layer "F.SilkS")
		)
		(fp_poly
			(pts
				(xy 1.255601 0.656399) (xy -1.255601 0.656399) (xy -1.255601 -0.6564) (xy 1.255601 -0.6564)
			)
			(stroke
				(width 0)
				(type default)
			)
			(fill no)
			(layer "F.CrtYd")
		)
		(fp_line
			(start -0.800001 -0.4)
			(end -0.800001 0.399999)
			(stroke
				(width 0.1)
				(type default)
			)
			(layer "F.Fab")
		)
		(fp_line
			(start -0.800001 0.399999)
			(end 0.800001 0.399999)
			(stroke
				(width 0.1)
				(type default)
			)
			(layer "F.Fab")
		)
		(fp_line
			(start 0.800001 -0.4)
			(end -0.800001 -0.4)
			(stroke
				(width 0.1)
				(type default)
			)
			(layer "F.Fab")
		)
		(fp_line
			(start 0.800001 0.399999)
			(end 0.800001 -0.4)
			(stroke
				(width 0.1)
				(type default)
			)
			(layer "F.Fab")
		)
		(pad "1" smd rect
			(at -0.650001 0)
			(size 0.7112 0.8128)
			(layers "F.Cu" "F.Mask" "F.Paste")
			(net "P3V3_B2_QSFP")
		)
		(pad "2" smd rect
			(at 0.650001 0 180)
			(size 0.7112 0.8128)
			(layers "F.Cu" "F.Mask" "F.Paste")
			(net "ETH10G_B2_TX_FAULT")
		)
	)
)
